# T6G (Grand Teton) — schematic netlist excerpt (pin names and nets, part order shuffled) for the footprints in the layout excerpt that follows; sources: Cadence DE-HDL packaged netlist, KiCad conversion of 04192023_DAF0TMB3IC0_F0TG_MB_C_brd_V02_OCP.brd

U308  74LVC2G07DW7  74LVC2G07DW-7 IC  pkg SOT363_0-65_2X1-25XC  page 241
  \1a\  = PWRGD_P3V3_AUX_PDB_R
  GND  = GND
  \2a\  = NC
  \2y\  = NC
  VCC  = P3V3_AUX
  \1y\  = PWRGD_P3V3_AUX_PDB_BUF_R

PR8011  Q_RES  0 5% CHIP  pkg 0402LF  page 217 : A = SVID_PVDDCR_CPU1_P1_SVC_R ; B = SVID_PVDDCR_CPU1_P1_SVC_R1

(kicad_pcb
	(version 20260206)
	(generator "pcbnew")
	(generator_version "10.0")
	(general
		(thickness 1.6)
		(legacy_teardrops no)
	)
	(paper "A4")
	(title_block
		(title "04192023_DAF0TMB3IC0_F0TG_MB_C_brd_V02_OCP.brd")
		(comment 1 "Grand Teton / footprints 3206-3207 of 8354")
	)
	(layers
		(0 "F.Cu" signal "TOP")
		(4 "In1.Cu" signal "GND")
		(6 "In2.Cu" signal "IN1")
		(8 "In3.Cu" signal "GND1")
		(10 "In4.Cu" signal "IN2")
		(12 "In5.Cu" signal "GND2")
		(14 "In6.Cu" signal "IN3")
		(16 "In7.Cu" signal "GND3")
		(18 "In8.Cu" signal "VCC")
		(20 "In9.Cu" signal "VCC1")
		(22 "In10.Cu" signal "GND4")
		(24 "In11.Cu" signal "IN4")
		(26 "In12.Cu" signal "GND5")
		(28 "In13.Cu" signal "IN5")
		(30 "In14.Cu" signal "GND6")
		(32 "In15.Cu" signal "IN6")
		(34 "In16.Cu" signal "GND7")
		(2 "B.Cu" signal "BOTTOM")
		(9 "F.Adhes" user "F.Adhesive")
		(11 "B.Adhes" user "B.Adhesive")
		(13 "F.Paste" user "Package Geometry/Pastemask Top")
		(15 "B.Paste" user "Package Geometry/Pastemask Bottom")
		(5 "F.SilkS" user "Ref Des/Silkscreen Top")
		(7 "B.SilkS" user "Ref Des/Silkscreen Bottom")
		(1 "F.Mask" user "Board Geometry/Soldermask Top")
		(3 "B.Mask" user "Board Geometry/Soldermask Bottom")
		(17 "Dwgs.User" user "User.Drawings")
		(19 "Cmts.User" user "User.Comments")
		(21 "Eco1.User" user "User.Eco1")
		(23 "Eco2.User" user "User.Eco2")
		(25 "Edge.Cuts" user "Board Geometry/Outline")
		(27 "Margin" user)
		(31 "F.CrtYd" user "Package Geometry/Place Bound Top")
		(29 "B.CrtYd" user "Package Geometry/Place Bound Bottom")
		(35 "F.Fab" user "Ref Des/Assembly Top")
		(33 "B.Fab" user "Ref Des/Assembly Bottom")
	)
	(footprint ""
		(layer "F.Cu")
		(at 24.765 -359.918)
		(property "Reference" "PR8011"
			(at 0 0 0)
			(layer "F.SilkS")
			(hide yes)
			(effects
				(font
					(size 1.27 1.27)
				)
			)
		)
		(property "Value" ""
			(at 0 0 0)
			(layer "F.Fab")
			(effects
				(font
					(size 1.27 1.27)
				)
			)
		)
		(duplicate_pad_numbers_are_jumpers no)
		(fp_line
			(start -0.7874 -0.4064)
			(end 0.7874 -0.4064)
			(stroke
				(width 0.1524)
				(type default)
			)
			(layer "F.SilkS")
		)
		(fp_line
			(start -0.7874 0.4064)
			(end -0.7874 -0.4064)
			(stroke
				(width 0.1524)
				(type default)
			)
			(layer "F.SilkS")
		)
		(fp_line
			(start 0.7874 -0.4064)
			(end 0.7874 0.4064)
			(stroke
				(width 0.1524)
				(type default)
			)
			(layer "F.SilkS")
		)
		(fp_line
			(start 0.7874 0.4064)
			(end -0.7874 0.4064)
			(stroke
				(width 0.1524)
				(type default)
			)
			(layer "F.SilkS")
		)
		(fp_line
			(start -0.67945 -0.305054)
			(end -0.12065 -0.305054)
			(stroke
				(width 0.1)
				(type default)
			)
			(layer "F.Fab")
		)
		(fp_line
			(start -0.67945 0.3048)
			(end -0.67945 -0.305054)
			(stroke
				(width 0.1)
				(type default)
			)
			(layer "F.Fab")
		)
		(fp_line
			(start -0.12065 -0.305054)
			(end -0.12065 -0.2794)
			(stroke
				(width 0.1)
				(type default)
			)
			(layer "F.Fab")
		)
		(fp_line
			(start -0.12065 -0.2794)
			(end 0.12065 -0.2794)
			(stroke
				(width 0.1)
				(type default)
			)
			(layer "F.Fab")
		)
		(fp_line
			(start -0.12065 0.2794)
			(end -0.12065 0.3048)
			(stroke
				(width 0.1)
				(type default)
			)
			(layer "F.Fab")
		)
		(fp_line
			(start -0.12065 0.3048)
			(end -0.67945 0.3048)
			(stroke
				(width 0.1)
				(type default)
			)
			(layer "F.Fab")
		)
		(fp_line
			(start 0.120396 0.2794)
			(end -0.12065 0.2794)
			(stroke
				(width 0.1)
				(type default)
			)
			(layer "F.Fab")
		)
		(fp_line
			(start 0.120396 0.3048)
			(end 0.120396 0.2794)
			(stroke
				(width 0.1)
				(type default)
			)
			(layer "F.Fab")
		)
		(fp_line
			(start 0.12065 -0.3048)
			(end 0.67945 -0.3048)
			(stroke
				(width 0.1)
				(type default)
			)
			(layer "F.Fab")
		)
		(fp_line
			(start 0.12065 -0.2794)
			(end 0.12065 -0.3048)
			(stroke
				(width 0.1)
				(type default)
			)
			(layer "F.Fab")
		)
		(fp_line
			(start 0.67945 -0.3048)
			(end 0.67945 0.3048)
			(stroke
				(width 0.1)
				(type default)
			)
			(layer "F.Fab")
		)
		(fp_line
			(start 0.67945 0.3048)
			(end 0.120396 0.3048)
			(stroke
				(width 0.1)
				(type default)
			)
			(layer "F.Fab")
		)
		(pad "1" smd circle
			(at -0.40005 0)
			(size 0 0)
			(layers "F.Cu" "F.Mask" "F.Paste")
			(net "SVID_PVDDCR_CPU1_P1_SVC_R")
		)
		(pad "2" smd circle
			(at 0.40005 0)
			(size 0 0)
			(layers "F.Cu" "F.Mask" "F.Paste")
			(net "SVID_PVDDCR_CPU1_P1_SVC_R1")
		)
	)
	(footprint ""
		(layer "F.Cu")
		(at 278.254206 -433.706016 -90)
		(property "Reference" "U308"
			(at 0.740664 -2.003552 0)
			(unlocked yes)
			(layer "F.SilkS")
			(effects
				(font
					(size 0.7874 0.5842)
					(thickness 0.1524)
				)
				(justify left)
			)
		)
		(property "Value" ""
			(at 0 0 270)
			(layer "F.Fab")
			(effects
				(font
					(size 1.27 1.27)
				)
			)
		)
		(duplicate_pad_numbers_are_jumpers no)
		(fp_line
			(start -1.38176 1.100074)
			(end 1.38176 1.100074)
			(stroke
				(width 0.1524)
				(type default)
			)
			(layer "F.SilkS")
		)
		(fp_line
			(start 1.38176 1.100074)
			(end 1.38176 -1.100074)
			(stroke
				(width 0.1524)
				(type default)
			)
			(layer "F.SilkS")
		)
		(fp_line
			(start 0 -0.508)
			(end -0.592074 -1.100074)
			(stroke
				(width 0.1524)
				(type default)
			)
			(layer "F.SilkS")
		)
		(fp_line
			(start -1.38176 -1.100074)
			(end -1.38176 1.100074)
			(stroke
				(width 0.1524)
				(type default)
			)
			(layer "F.SilkS")
		)
		(fp_line
			(start -0.592074 -1.100074)
			(end -1.38176 -1.100074)
			(stroke
				(width 0.1524)
				(type default)
			)
			(layer "F.SilkS")
		)
		(fp_line
			(start 0.592074 -1.100074)
			(end 0 -0.508)
			(stroke
				(width 0.1524)
				(type default)
			)
			(layer "F.SilkS")
		)
		(fp_line
			(start 1.38176 -1.100074)
			(end 0.592074 -1.100074)
			(stroke
				(width 0.1524)
				(type default)
			)
			(layer "F.SilkS")
		)
		(fp_poly
			(pts
				(xy -1.528318 -1.73355) (xy -1.372362 -1.26619) (xy -1.839722 -1.422146)
			)
			(stroke
				(width 0)
				(type default)
			)
			(fill yes)
			(layer "F.SilkS")
		)
		(fp_line
			(start -0.674878 1.100074)
			(end 0.674878 1.100074)
			(stroke
				(width 0.1)
				(type default)
			)
			(layer "F.Fab")
		)
		(fp_line
			(start 0.674878 1.100074)
			(end 0.674878 -1.100074)
			(stroke
				(width 0.1)
				(type default)
			)
			(layer "F.Fab")
		)
		(fp_line
			(start -0.674878 -1.100074)
			(end -0.674878 1.100074)
			(stroke
				(width 0.1)
				(type default)
			)
			(layer "F.Fab")
		)
		(fp_line
			(start 0.674878 -1.100074)
			(end -0.674878 -1.100074)
			(stroke
				(width 0.1)
				(type default)
			)
			(layer "F.Fab")
		)
		(fp_poly
			(pts
				(xy -1.9431 -0.870204) (xy -1.50241 -0.649986) (xy -1.9431 -0.429768)
			)
			(stroke
				(width 0)
				(type default)
			)
			(fill yes)
			(layer "F.Fab")
		)
		(pad "1" smd rect
			(at -0.94996 -0.649986 180)
			(size 0.4318 0.6096)
			(layers "F.Cu" "F.Mask" "F.Paste")
			(net "PWRGD_P3V3_AUX_PDB_R")
		)
		(pad "2" smd rect
			(at -0.94996 0 180)
			(size 0.4318 0.6096)
			(layers "F.Cu" "F.Mask" "F.Paste")
			(net "GND")
		)
		(pad "3" smd rect
			(at -0.94996 0.649986 180)
			(size 0.4318 0.6096)
			(layers "F.Cu" "F.Mask" "F.Paste")
			(net "Net_10754")
		)
		(pad "4" smd rect
			(at 0.94996 0.649986 180)
			(size 0.4318 0.6096)
			(layers "F.Cu" "F.Mask" "F.Paste")
			(net "Net_10753")
		)
		(pad "5" smd rect
			(at 0.94996 0 180)
			(size 0.4318 0.6096)
			(layers "F.Cu" "F.Mask" "F.Paste")
			(net "P3V3_AUX")
		)
		(pad "6" smd rect
			(at 0.94996 -0.649986 180)
			(size 0.4318 0.6096)
			(layers "F.Cu" "F.Mask" "F.Paste")
			(net "PWRGD_P3V3_AUX_PDB_BUF_R")
		)
	)
)
